(kicad_pcb
	(version 20260206)
	(generator "pcbnew")
	(generator_version "10.0")
	(general
		(thickness 1.21888)
		(legacy_teardrops no)
	)
	(paper "A4")
	(title_block
		(title "timecard-v9 — TimeCard-DC-V9_EXP.PcbDoc")
		(comment 1 "Time Appliance Project (Time Card) / footprints 244-248 of 402")
	)
	(layers
		(0 "F.Cu" signal "TOP")
		(4 "In1.Cu" signal "SGND")
		(6 "In2.Cu" signal "IN1")
		(8 "In3.Cu" signal "IN2")
		(10 "In4.Cu" signal "SGND1")
		(2 "B.Cu" signal "BOTTOM")
		(9 "F.Adhes" user "F.Adhesive")
		(11 "B.Adhes" user "B.Adhesive")
		(13 "F.Paste" user "Top Paste")
		(15 "B.Paste" user "Bottom Paste")
		(5 "F.SilkS" user "Top Overlay")
		(7 "B.SilkS" user "Bottom Overlay")
		(1 "F.Mask" user "Top Solder")
		(3 "B.Mask" user "Bottom Solder")
		(17 "Dwgs.User" user "User.Drawings")
		(19 "Cmts.User" user "User.Comments")
		(21 "Eco1.User" user "User.Eco1")
		(23 "Eco2.User" user "User.Eco2")
		(25 "Edge.Cuts" user)
		(27 "Margin" user)
		(31 "F.CrtYd" user "Top Courtyard")
		(29 "B.CrtYd" user "Bottom Courtyard")
		(35 "F.Fab" user "Top Component Center")
		(33 "B.Fab" user "Bottom Component Center")
	)
	(footprint "Vault:FP-BNO055-MFG"
		(layer "F.Cu")
		(at 113.58072 87.2662)
		(property "Reference" "U13"
			(at -3.632189 1.8214 90)
			(unlocked yes)
			(layer "F.SilkS")
			(effects
				(font
					(size 0.762 0.762)
					(thickness 0.2286)
				)
			)
		)
		(property "Value" "BNO055"
			(at 1.94175 3.494271 0)
			(unlocked yes)
			(layer "F.SilkS")
			(hide yes)
			(effects
				(font
					(size 0.762 0.762)
					(thickness 0.2286)
				)
			)
		)
		(sheetname "05-GPS_IMU_SENSORS")
		(sheetfile "05-GPS_IMU_SENSORS.kicad_sch")
		(duplicate_pad_numbers_are_jumpers no)
		(fp_rect
			(start -1.82503 -2.04997)
			(end -1.30003 -2.44997)
			(stroke
				(width 0)
				(type default)
			)
			(fill yes)
			(layer "F.Mask")
		)
		(fp_rect
			(start -1.82503 -0.04997)
			(end -1.30003 -0.44997)
			(stroke
				(width 0)
				(type default)
			)
			(fill yes)
			(layer "F.Mask")
		)
		(fp_rect
			(start -1.82503 0.45003)
			(end -1.30003 0.05003)
			(stroke
				(width 0)
				(type default)
			)
			(fill yes)
			(layer "F.Mask")
		)
		(fp_rect
			(start -1.82503 2.45003)
			(end -1.30003 2.05003)
			(stroke
				(width 0)
				(type default)
			)
			(fill yes)
			(layer "F.Mask")
		)
		(fp_rect
			(start -1.825 -1.55)
			(end -1.3 -1.95)
			(stroke
				(width 0)
				(type default)
			)
			(fill yes)
			(layer "F.Mask")
		)
		(fp_rect
			(start -1.825 -0.55)
			(end -1.3 -0.95)
			(stroke
				(width 0)
				(type default)
			)
			(fill yes)
			(layer "F.Mask")
		)
		(fp_rect
			(start -1.825 0.95)
			(end -1.3 0.55)
			(stroke
				(width 0)
				(type default)
			)
			(fill yes)
			(layer "F.Mask")
		)
		(fp_rect
			(start -1.825 1.95)
			(end -1.3 1.55)
			(stroke
				(width 0)
				(type default)
			)
			(fill yes)
			(layer "F.Mask")
		)
		(fp_rect
			(start -1.82497 -1.05003)
			(end -1.29997 -1.45003)
			(stroke
				(width 0)
				(type default)
			)
			(fill yes)
			(layer "F.Mask")
		)
		(fp_rect
			(start -1.82497 1.44997)
			(end -1.29997 1.04997)
			(stroke
				(width 0)
				(type default)
			)
			(fill yes)
			(layer "F.Mask")
		)
		(fp_rect
			(start -0.9 -2.05)
			(end -0.59999 -2.575)
			(stroke
				(width 0)
				(type default)
			)
			(fill yes)
			(layer "F.Mask")
		)
		(fp_rect
			(start -0.9 2.575)
			(end -0.59999 2.05)
			(stroke
				(width 0)
				(type default)
			)
			(fill yes)
			(layer "F.Mask")
		)
		(fp_rect
			(start -0.40001 2.57498)
			(end -0.10001 2.04998)
			(stroke
				(width 0)
				(type default)
			)
			(fill yes)
			(layer "F.Mask")
		)
		(fp_rect
			(start -0.39998 -2.04998)
			(end -0.09998 -2.57498)
			(stroke
				(width 0)
				(type default)
			)
			(fill yes)
			(layer "F.Mask")
		)
		(fp_rect
			(start 0.09999 2.57498)
			(end 0.39999 2.04998)
			(stroke
				(width 0)
				(type default)
			)
			(fill yes)
			(layer "F.Mask")
		)
		(fp_rect
			(start 0.10002 -2.04998)
			(end 0.40002 -2.57498)
			(stroke
				(width 0)
				(type default)
			)
			(fill yes)
			(layer "F.Mask")
		)
		(fp_rect
			(start 0.6 -2.05)
			(end 0.9 -2.575)
			(stroke
				(width 0)
				(type default)
			)
			(fill yes)
			(layer "F.Mask")
		)
		(fp_rect
			(start 0.6 2.575)
			(end 0.9 2.05)
			(stroke
				(width 0)
				(type default)
			)
			(fill yes)
			(layer "F.Mask")
		)
		(fp_rect
			(start 1.29998 -1.04997)
			(end 1.82498 -1.44997)
			(stroke
				(width 0)
				(type default)
			)
			(fill yes)
			(layer "F.Mask")
		)
		(fp_rect
			(start 1.29998 1.45003)
			(end 1.82498 1.05003)
			(stroke
				(width 0)
				(type default)
			)
			(fill yes)
			(layer "F.Mask")
		)
		(fp_rect
			(start 1.3 -1.55)
			(end 1.825 -1.95)
			(stroke
				(width 0)
				(type default)
			)
			(fill yes)
			(layer "F.Mask")
		)
		(fp_rect
			(start 1.3 -0.55)
			(end 1.825 -0.95)
			(stroke
				(width 0)
				(type default)
			)
			(fill yes)
			(layer "F.Mask")
		)
		(fp_rect
			(start 1.3 0.95)
			(end 1.825 0.55)
			(stroke
				(width 0)
				(type default)
			)
			(fill yes)
			(layer "F.Mask")
		)
		(fp_rect
			(start 1.3 1.95)
			(end 1.825 1.55)
			(stroke
				(width 0)
				(type default)
			)
			(fill yes)
			(layer "F.Mask")
		)
		(fp_rect
			(start 1.30003 -2.05003)
			(end 1.82503 -2.45003)
			(stroke
				(width 0)
				(type default)
			)
			(fill yes)
			(layer "F.Mask")
		)
		(fp_rect
			(start 1.30003 -0.05003)
			(end 1.82503 -0.45003)
			(stroke
				(width 0)
				(type default)
			)
			(fill yes)
			(layer "F.Mask")
		)
		(fp_rect
			(start 1.30003 0.44997)
			(end 1.82503 0.04997)
			(stroke
				(width 0)
				(type default)
			)
			(fill yes)
			(layer "F.Mask")
		)
		(fp_rect
			(start 1.30003 2.44997)
			(end 1.82503 2.04997)
			(stroke
				(width 0)
				(type default)
			)
			(fill yes)
			(layer "F.Mask")
		)
		(fp_line
			(start -2.25 2.65)
			(end -2.25 -2.65)
			(stroke
				(width 0.2)
				(type solid)
			)
			(layer "F.SilkS")
		)
		(fp_line
			(start 2.25 2.65)
			(end 2.25 -2.65)
			(stroke
				(width 0.2)
				(type solid)
			)
			(layer "F.SilkS")
		)
		(fp_circle
			(center 2.75 -2.25)
			(end 2.75 -2.375)
			(stroke
				(width 0.25)
				(type solid)
			)
			(fill no)
			(layer "F.SilkS")
		)
		(fp_line
			(start -2.45 -3.15)
			(end 2.45 -3.15)
			(stroke
				(width 0.2)
				(type solid)
			)
			(layer "F.CrtYd")
		)
		(fp_line
			(start -2.45 3.15)
			(end -2.45 -3.15)
			(stroke
				(width 0.2)
				(type solid)
			)
			(layer "F.CrtYd")
		)
		(fp_line
			(start -2.45 3.15)
			(end 2.45 3.15)
			(stroke
				(width 0.2)
				(type solid)
			)
			(layer "F.CrtYd")
		)
		(fp_line
			(start 2.45 3.15)
			(end 2.45 -3.15)
			(stroke
				(width 0.2)
				(type solid)
			)
			(layer "F.CrtYd")
		)
		(fp_line
			(start -2.45 -3.15)
			(end 2.45 -3.15)
			(stroke
				(width 0.2)
				(type solid)
			)
			(layer "F.Fab")
		)
		(fp_line
			(start -2.45 3.15)
			(end -2.45 -3.15)
			(stroke
				(width 0.2)
				(type solid)
			)
			(layer "F.Fab")
		)
		(fp_line
			(start -2.45 3.15)
			(end 2.45 3.15)
			(stroke
				(width 0.2)
				(type solid)
			)
			(layer "F.Fab")
		)
		(fp_line
			(start -0.735 0)
			(end 0.735 0)
			(stroke
				(width 0.1)
				(type solid)
			)
			(layer "F.Fab")
		)
		(fp_line
			(start 0 0.735)
			(end 0 -0.735)
			(stroke
				(width 0.1)
				(type solid)
			)
			(layer "F.Fab")
		)
		(fp_line
			(start 2.45 3.15)
			(end 2.45 -3.15)
			(stroke
				(width 0.2)
				(type solid)
			)
			(layer "F.Fab")
		)
		(fp_text user "${REFERENCE}"
			(at 0 0.28425 360)
			(unlocked yes)
			(layer "F.Fab")
			(effects
				(font
					(face "Arial")
					(size 0.63 0.63)
					(thickness 0.1)
				)
				(justify left bottom)
			)
		)
		(pad "1" smd rect
			(at 1.5625 -2.25)
			(size 0.475 0.35)
			(layers "F.Cu" "F.Mask" "F.Paste")
			(solder_mask_margin -1000)
			(solder_paste_margin 0)
		)
		(pad "2" smd rect
			(at 0.75 -2.3125)
			(size 0.25 0.475)
			(layers "F.Cu" "F.Mask" "F.Paste")
			(net "GND")
			(solder_mask_margin -1000)
			(solder_paste_margin 0)
		)
		(pad "3" smd rect
			(at 0.25 -2.3125)
			(size 0.25 0.475)
			(layers "F.Cu" "F.Mask" "F.Paste")
			(net "BNO_P3V3")
			(solder_mask_margin -1000)
			(solder_paste_margin 0)
		)
		(pad "4" smd rect
			(at -0.25 -2.3125)
			(size 0.25 0.475)
			(layers "F.Cu" "F.Mask" "F.Paste")
			(net "NetR51_2")
			(solder_mask_margin -1000)
			(solder_paste_margin 0)
		)
		(pad "5" smd rect
			(at -0.75 -2.3125)
			(size 0.25 0.475)
			(layers "F.Cu" "F.Mask" "F.Paste")
			(net "GND")
			(solder_mask_margin -1000)
			(solder_paste_margin 0)
		)
		(pad "6" smd rect
			(at -1.56249 -2.25)
			(size 0.475 0.35)
			(layers "F.Cu" "F.Mask" "F.Paste")
			(net "GND")
			(solder_mask_margin -1000)
			(solder_paste_margin 0)
		)
		(pad "7" smd rect
			(at -1.56249 -1.75)
			(size 0.475 0.35)
			(layers "F.Cu" "F.Mask" "F.Paste")
			(net "NetR57_2")
			(solder_mask_margin -1000)
			(solder_paste_margin 0)
		)
		(pad "8" smd rect
			(at -1.56249 -1.25)
			(size 0.475 0.35)
			(layers "F.Cu" "F.Mask" "F.Paste")
			(net "NetR58_2")
			(solder_mask_margin -1000)
			(solder_paste_margin 0)
		)
		(pad "9" smd rect
			(at -1.56249 -0.75)
			(size 0.475 0.35)
			(layers "F.Cu" "F.Mask" "F.Paste")
			(net "NetC65_1")
			(solder_mask_margin -1000)
			(solder_paste_margin 0)
		)
		(pad "10" smd rect
			(at -1.56249 -0.25)
			(size 0.475 0.35)
			(layers "F.Cu" "F.Mask" "F.Paste")
			(net "NetR55_2")
			(solder_mask_margin -1000)
			(solder_paste_margin 0)
		)
		(pad "11" smd rect
			(at -1.56249 0.25)
			(size 0.475 0.35)
			(layers "F.Cu" "F.Mask" "F.Paste")
			(net "NetR52_1")
			(solder_mask_margin -1000)
			(solder_paste_margin 0)
		)
		(pad "12" smd rect
			(at -1.56249 0.75)
			(size 0.475 0.35)
			(layers "F.Cu" "F.Mask" "F.Paste")
			(solder_mask_margin -1000)
			(solder_paste_margin 0)
		)
		(pad "13" smd rect
			(at -1.56249 1.25)
			(size 0.475 0.35)
			(layers "F.Cu" "F.Mask" "F.Paste")
			(solder_mask_margin -1000)
			(solder_paste_margin 0)
		)
		(pad "14" smd rect
			(at -1.56249 1.75)
			(size 0.475 0.35)
			(layers "F.Cu" "F.Mask" "F.Paste")
			(net "BNO_INT")
			(solder_mask_margin -1000)
			(solder_paste_margin 0)
		)
		(pad "15" smd rect
			(at -1.56249 2.25)
			(size 0.475 0.35)
			(layers "F.Cu" "F.Mask" "F.Paste")
			(solder_mask_margin -1000)
			(solder_paste_margin 0)
		)
		(pad "16" smd rect
			(at -0.75 2.3125)
			(size 0.25 0.475)
			(layers "F.Cu" "F.Mask" "F.Paste")
			(solder_mask_margin -1000)
			(solder_paste_margin 0)
		)
		(pad "17" smd rect
			(at -0.25 2.3125)
			(size 0.25 0.475)
			(layers "F.Cu" "F.Mask" "F.Paste")
			(net "NetR53_1")
			(solder_mask_margin -1000)
			(solder_paste_margin 0)
		)
		(pad "18" smd rect
			(at 0.25 2.3125)
			(size 0.25 0.475)
			(layers "F.Cu" "F.Mask" "F.Paste")
			(net "GND")
			(solder_mask_margin -1000)
			(solder_paste_margin 0)
		)
		(pad "19" smd rect
			(at 0.75 2.3125)
			(size 0.25 0.475)
			(layers "F.Cu" "F.Mask" "F.Paste")
			(net "SENS_I2C_SCL")
			(solder_mask_margin -1000)
			(solder_paste_margin 0)
		)
		(pad "20" smd rect
			(at 1.5625 2.25)
			(size 0.475 0.35)
			(layers "F.Cu" "F.Mask" "F.Paste")
			(net "SENS_I2C_SDA")
			(solder_mask_margin -1000)
			(solder_paste_margin 0)
		)
		(pad "21" smd rect
			(at 1.5625 1.75)
			(size 0.475 0.35)
			(layers "F.Cu" "F.Mask" "F.Paste")
			(solder_mask_margin -1000)
			(solder_paste_margin 0)
		)
		(pad "22" smd rect
			(at 1.5625 1.25)
			(size 0.475 0.35)
			(layers "F.Cu" "F.Mask" "F.Paste")
			(solder_mask_margin -1000)
			(solder_paste_margin 0)
		)
		(pad "23" smd rect
			(at 1.5625 0.75)
			(size 0.475 0.35)
			(layers "F.Cu" "F.Mask" "F.Paste")
			(solder_mask_margin -1000)
			(solder_paste_margin 0)
		)
		(pad "24" smd rect
			(at 1.5625 0.25)
			(size 0.475 0.35)
			(layers "F.Cu" "F.Mask" "F.Paste")
			(solder_mask_margin -1000)
			(solder_paste_margin 0)
		)
		(pad "25" smd rect
			(at 1.5625 -0.25)
			(size 0.475 0.35)
			(layers "F.Cu" "F.Mask" "F.Paste")
			(net "GND")
			(solder_mask_margin -1000)
			(solder_paste_margin 0)
		)
		(pad "26" smd rect
			(at 1.5625 -0.75)
			(size 0.475 0.35)
			(layers "F.Cu" "F.Mask" "F.Paste")
			(net "BNO_XOUT32")
			(solder_mask_margin -1000)
			(solder_paste_margin 0)
		)
		(pad "27" smd rect
			(at 1.5625 -1.25)
			(size 0.475 0.35)
			(layers "F.Cu" "F.Mask" "F.Paste")
			(net "BNO_XIN32")
			(solder_mask_margin -1000)
			(solder_paste_margin 0)
		)
		(pad "28" smd rect
			(at 1.5625 -1.75)
			(size 0.475 0.35)
			(layers "F.Cu" "F.Mask" "F.Paste")
			(net "BNO_P3V3")
			(solder_mask_margin -1000)
			(solder_paste_margin 0)
		)
	)
	(footprint "Vault:RESC1005X40X25LL05T10"
		(layer "F.Cu")
		(at 146.1216 103.3162)
		(property "Reference" "R107"
			(at 1.57942 -1.122249 0)
			(unlocked yes)
			(layer "F.SilkS")
			(effects
				(font
					(size 0.762 0.762)
					(thickness 0.2286)
				)
			)
		)
		(property "Value" "DNI_49.9_1%_0402"
			(at -2.579871 11.74372 270)
			(unlocked yes)
			(layer "F.SilkS")
			(hide yes)
			(effects
				(font
					(size 0.762 0.762)
					(thickness 0.2286)
				)
			)
		)
		(sheetname "09-USBUart_PPSMUX_UARTMUX")
		(sheetfile "09-USBUart_PPSMUX_UARTMUX.kicad_sch")
		(duplicate_pad_numbers_are_jumpers no)
		(pad "1" smd rect
			(at -0.375 0 90)
			(size 0.45 0.5)
			(layers "F.Cu" "F.Mask" "F.Paste")
			(net "FPGA_MAC_PPS_IN0-")
		)
		(pad "2" smd rect
			(at 0.375 0 90)
			(size 0.45 0.5)
			(layers "F.Cu" "F.Mask" "F.Paste")
			(net "FPGA_MAC_PPS_DIFF_IN0")
		)
	)
	(footprint "Vault:RESC1005X40X25LL05T10"
		(layer "F.Cu")
		(at 192.2216 128.9162 90)
		(property "Reference" "R142"
			(at 0.90981 -2.466549 90)
			(unlocked yes)
			(layer "F.SilkS")
			(effects
				(font
					(size 0.762 0.762)
					(thickness 0.2032)
				)
			)
		)
		(property "Value" "49.9_1%_0402"
			(at -2.579871 8.798265 0)
			(unlocked yes)
			(layer "F.SilkS")
			(hide yes)
			(effects
				(font
					(size 0.762 0.762)
					(thickness 0.2032)
				)
			)
		)
		(sheetname "11-M2_RCB_MUX")
		(sheetfile "11-M2_RCB_MUX.kicad_sch")
		(duplicate_pad_numbers_are_jumpers no)
		(pad "1" smd rect
			(at -0.375 0 180)
			(size 0.45 0.5)
			(layers "F.Cu" "F.Mask" "F.Paste")
			(net "NetR142_1")
		)
		(pad "2" smd rect
			(at 0.375 0 180)
			(size 0.45 0.5)
			(layers "F.Cu" "F.Mask" "F.Paste")
			(net "GPS2_TX")
		)
	)
	(footprint "Vault:RESC3216X89X64NL25T25"
		(layer "F.Cu")
		(at 223.2466 68.4162)
		(property "Reference" "R7"
			(at 2.475 0.493345 0)
			(unlocked yes)
			(layer "F.SilkS")
			(effects
				(font
					(size 0.762 0.762)
					(thickness 0.2286)
				)
				(justify left bottom)
			)
		)
		(property "Value" "2mOhm_1%_1206"
			(at 7.6471 8.378245 0)
			(unlocked yes)
			(layer "F.SilkS")
			(hide yes)
			(effects
				(font
					(size 0.762 0.762)
					(thickness 0.2286)
				)
				(justify left bottom)
			)
		)
		(sheetname "03-POWER")
		(sheetfile "03-POWER.kicad_sch")
		(duplicate_pad_numbers_are_jumpers no)
		(fp_line
			(start -0.2 -0.825)
			(end 0.2 -0.825)
			(stroke
				(width 0.2)
				(type solid)
			)
			(layer "F.SilkS")
		)
		(fp_line
			(start -0.2 0.825)
			(end 0.2 0.825)
			(stroke
				(width 0.2)
				(type solid)
			)
			(layer "F.SilkS")
		)
		(pad "1" smd rect
			(at -1.325 0 90)
			(size 1.85 1.5)
			(layers "F.Cu" "F.Mask" "F.Paste")
			(net "+12V_SENS")
		)
		(pad "2" smd rect
			(at 1.325 0 90)
			(size 1.85 1.5)
			(layers "F.Cu" "F.Mask" "F.Paste")
			(net "+12V")
		)
	)
	(footprint "Vault:CTS-219-2LPST_V"
		(layer "F.Cu")
		(at 226.4216 98.0162 180)
		(property "Reference" "SW2"
			(at -2.7968 -3.973069 180)
			(unlocked yes)
			(layer "F.SilkS")
			(effects
				(font
					(size 0.762 0.762)
					(thickness 0.2032)
				)
			)
		)
		(property "Value" "219-2LPST"
			(at 5.115805 7.659871 180)
			(unlocked yes)
			(layer "F.SilkS")
			(hide yes)
			(effects
				(font
					(size 0.762 0.762)
					(thickness 0.2032)
				)
			)
		)
		(sheetname "08-DIPSwitches_I2C")
		(sheetfile "08-DIPSwitches_I2C.kicad_sch")
		(duplicate_pad_numbers_are_jumpers no)
		(fp_line
			(start 3.3528 3.2766)
			(end -3.3528 3.2766)
			(stroke
				(width 0.2)
				(type solid)
			)
			(layer "F.SilkS")
		)
		(fp_line
			(start 3.3528 2.2292)
			(end 3.3528 3.2766)
			(stroke
				(width 0.2)
				(type solid)
			)
			(layer "F.SilkS")
		)
		(fp_line
			(start 3.3528 -3.2766)
			(end 3.3528 -2.2292)
			(stroke
				(width 0.2)
				(type solid)
			)
			(layer "F.SilkS")
		)
		(fp_line
			(start 3.3528 -3.2766)
			(end -3.3528 -3.2766)
			(stroke
				(width 0.2)
				(type solid)
			)
			(layer "F.SilkS")
		)
		(fp_line
			(start -3.3528 2.2292)
			(end -3.3528 3.2766)
			(stroke
				(width 0.2)
				(type solid)
			)
			(layer "F.SilkS")
		)
		(fp_line
			(start -3.3528 -3.2766)
			(end -3.3528 -2.2292)
			(stroke
				(width 0.2)
				(type solid)
			)
			(layer "F.SilkS")
		)
		(fp_circle
			(center -4.3 -2.9)
			(end -4.3 -2.775)
			(stroke
				(width 0.25)
				(type solid)
			)
			(fill no)
			(layer "F.SilkS")
		)
		(pad "1" smd rect
			(at -4.3053 -1.27 90)
			(size 1.1176 2.4384)
			(layers "F.Cu" "F.Mask" "F.Paste")
			(net "GND")
		)
		(pad "2" smd rect
			(at -4.3053 1.27 90)
			(size 1.1176 2.4384)
			(layers "F.Cu" "F.Mask" "F.Paste")
			(net "GND")
		)
		(pad "3" smd rect
			(at 4.3053 1.27 90)
			(size 1.1176 2.4384)
			(layers "F.Cu" "F.Mask" "F.Paste")
			(net "DIP_SW_GPS1_SEL")
		)
		(pad "4" smd rect
			(at 4.3053 -1.27 90)
			(size 1.1176 2.4384)
			(layers "F.Cu" "F.Mask" "F.Paste")
			(net "DIP_SW_GPS2_SEL")
		)
	)
)
